(kicad_pcb
	(version 20260206)
	(generator "pcbnew")
	(generator_version "10.0")
	(general
		(thickness 1.6)
		(legacy_teardrops no)
	)
	(paper "A4")
	(title_block
		(title "01162023_DA0F0TEBIF0_F0T_Expander_BD_F_brd_V02_OCP.brd")
		(comment 1 "Grand Teton / footprints 5030-5035 of 9728")
	)
	(layers
		(0 "F.Cu" signal "TOP")
		(4 "In1.Cu" signal "GND")
		(6 "In2.Cu" signal "VCC")
		(8 "In3.Cu" signal "VCC1")
		(10 "In4.Cu" signal "GND1")
		(12 "In5.Cu" signal "IN1")
		(14 "In6.Cu" signal "GND2")
		(16 "In7.Cu" signal "IN2")
		(18 "In8.Cu" signal "GND3")
		(20 "In9.Cu" signal "IN3")
		(22 "In10.Cu" signal "GND4")
		(24 "In11.Cu" signal "IN4")
		(26 "In12.Cu" signal "GND5")
		(28 "In13.Cu" signal "IN5")
		(30 "In14.Cu" signal "GND6")
		(32 "In15.Cu" signal "IN6")
		(34 "In16.Cu" signal "GND7")
		(2 "B.Cu" signal "BOTTOM")
		(9 "F.Adhes" user "F.Adhesive")
		(11 "B.Adhes" user "B.Adhesive")
		(13 "F.Paste" user "Package Geometry/Pastemask Top")
		(15 "B.Paste" user "Package Geometry/Pastemask Bottom")
		(5 "F.SilkS" user "Ref Des/Silkscreen Top")
		(7 "B.SilkS" user "Ref Des/Silkscreen Bottom")
		(1 "F.Mask" user "Board Geometry/Soldermask Top")
		(3 "B.Mask" user "Board Geometry/Soldermask Bottom")
		(17 "Dwgs.User" user "User.Drawings")
		(19 "Cmts.User" user "User.Comments")
		(21 "Eco1.User" user "User.Eco1")
		(23 "Eco2.User" user "User.Eco2")
		(25 "Edge.Cuts" user "Board Geometry/Outline")
		(27 "Margin" user)
		(31 "F.CrtYd" user "Package Geometry/Place Bound Top")
		(29 "B.CrtYd" user "Package Geometry/Place Bound Bottom")
		(35 "F.Fab" user "Ref Des/Assembly Top")
		(33 "B.Fab" user "Ref Des/Assembly Bottom")
	)
	(footprint ""
		(layer "F.Cu")
		(at 381.009144 -26.03373)
		(property "Reference" "R4078"
			(at 0 0 0)
			(layer "F.SilkS")
			(hide yes)
			(effects
				(font
					(size 1.27 1.27)
				)
			)
		)
		(property "Value" ""
			(at 0 0 0)
			(layer "F.Fab")
			(effects
				(font
					(size 1.27 1.27)
				)
			)
		)
		(duplicate_pad_numbers_are_jumpers no)
		(fp_line
			(start -0.7874 -0.4064)
			(end 0.7874 -0.4064)
			(stroke
				(width 0.1524)
				(type default)
			)
			(layer "F.SilkS")
		)
		(fp_line
			(start -0.7874 0.4064)
			(end -0.7874 -0.4064)
			(stroke
				(width 0.1524)
				(type default)
			)
			(layer "F.SilkS")
		)
		(fp_line
			(start 0.7874 -0.4064)
			(end 0.7874 0.4064)
			(stroke
				(width 0.1524)
				(type default)
			)
			(layer "F.SilkS")
		)
		(fp_line
			(start 0.7874 0.4064)
			(end -0.7874 0.4064)
			(stroke
				(width 0.1524)
				(type default)
			)
			(layer "F.SilkS")
		)
		(fp_line
			(start -0.67945 -0.305054)
			(end -0.12065 -0.305054)
			(stroke
				(width 0.1)
				(type default)
			)
			(layer "F.Fab")
		)
		(fp_line
			(start -0.67945 0.3048)
			(end -0.67945 -0.305054)
			(stroke
				(width 0.1)
				(type default)
			)
			(layer "F.Fab")
		)
		(fp_line
			(start -0.12065 -0.305054)
			(end -0.12065 -0.2794)
			(stroke
				(width 0.1)
				(type default)
			)
			(layer "F.Fab")
		)
		(fp_line
			(start -0.12065 -0.2794)
			(end 0.12065 -0.2794)
			(stroke
				(width 0.1)
				(type default)
			)
			(layer "F.Fab")
		)
		(fp_line
			(start -0.12065 0.2794)
			(end -0.12065 0.3048)
			(stroke
				(width 0.1)
				(type default)
			)
			(layer "F.Fab")
		)
		(fp_line
			(start -0.12065 0.3048)
			(end -0.67945 0.3048)
			(stroke
				(width 0.1)
				(type default)
			)
			(layer "F.Fab")
		)
		(fp_line
			(start 0.120396 0.2794)
			(end -0.12065 0.2794)
			(stroke
				(width 0.1)
				(type default)
			)
			(layer "F.Fab")
		)
		(fp_line
			(start 0.120396 0.3048)
			(end 0.120396 0.2794)
			(stroke
				(width 0.1)
				(type default)
			)
			(layer "F.Fab")
		)
		(fp_line
			(start 0.12065 -0.3048)
			(end 0.67945 -0.3048)
			(stroke
				(width 0.1)
				(type default)
			)
			(layer "F.Fab")
		)
		(fp_line
			(start 0.12065 -0.2794)
			(end 0.12065 -0.3048)
			(stroke
				(width 0.1)
				(type default)
			)
			(layer "F.Fab")
		)
		(fp_line
			(start 0.67945 -0.3048)
			(end 0.67945 0.3048)
			(stroke
				(width 0.1)
				(type default)
			)
			(layer "F.Fab")
		)
		(fp_line
			(start 0.67945 0.3048)
			(end 0.120396 0.3048)
			(stroke
				(width 0.1)
				(type default)
			)
			(layer "F.Fab")
		)
		(pad "1" smd circle
			(at -0.40005 0)
			(size 0 0)
			(layers "F.Cu" "F.Mask" "F.Paste")
			(net "P3V3_AUX")
		)
		(pad "2" smd circle
			(at 0.40005 0)
			(size 0 0)
			(layers "F.Cu" "F.Mask" "F.Paste")
			(net "PRSNT_SSD13_R_N")
		)
	)
	(footprint ""
		(layer "F.Cu")
		(at 212.080602 -239.862868 90)
		(property "Reference" "U123"
			(at -1.395222 -2.96291 90)
			(unlocked yes)
			(layer "F.SilkS")
			(effects
				(font
					(size 0.7874 0.5842)
					(thickness 0.1524)
				)
				(justify left)
			)
		)
		(property "Value" ""
			(at 0 0 90)
			(layer "F.Fab")
			(effects
				(font
					(size 1.27 1.27)
				)
			)
		)
		(duplicate_pad_numbers_are_jumpers no)
		(fp_line
			(start 1.463548 -1.549908)
			(end 1.463548 1.549908)
			(stroke
				(width 0.1524)
				(type default)
			)
			(layer "F.SilkS")
		)
		(fp_line
			(start 0.762 -1.549908)
			(end 1.463548 -1.549908)
			(stroke
				(width 0.1524)
				(type default)
			)
			(layer "F.SilkS")
		)
		(fp_line
			(start -0.787908 -1.549908)
			(end 0 -0.762)
			(stroke
				(width 0.1524)
				(type default)
			)
			(layer "F.SilkS")
		)
		(fp_line
			(start -1.463548 -1.549908)
			(end -0.787908 -1.549908)
			(stroke
				(width 0.1524)
				(type default)
			)
			(layer "F.SilkS")
		)
		(fp_line
			(start 0 -0.762)
			(end 0.762 -1.549908)
			(stroke
				(width 0.1524)
				(type default)
			)
			(layer "F.SilkS")
		)
		(fp_line
			(start 1.463548 1.549908)
			(end -1.463548 1.549908)
			(stroke
				(width 0.1524)
				(type default)
			)
			(layer "F.SilkS")
		)
		(fp_line
			(start -1.463548 1.549908)
			(end -1.463548 -1.549908)
			(stroke
				(width 0.1524)
				(type default)
			)
			(layer "F.SilkS")
		)
		(fp_poly
			(pts
				(xy -2.227834 -2.2225) (xy -2.537714 -1.60274) (xy -2.847594 -2.2225)
			)
			(stroke
				(width 0)
				(type default)
			)
			(fill yes)
			(layer "F.SilkS")
		)
		(fp_line
			(start 1.549908 -1.549908)
			(end 1.549908 1.549908)
			(stroke
				(width 0.1)
				(type default)
			)
			(layer "F.Fab")
		)
		(fp_line
			(start -1.549908 -1.549908)
			(end 1.549908 -1.549908)
			(stroke
				(width 0.1)
				(type default)
			)
			(layer "F.Fab")
		)
		(fp_line
			(start 1.549908 1.549908)
			(end -1.549908 1.549908)
			(stroke
				(width 0.1)
				(type default)
			)
			(layer "F.Fab")
		)
		(fp_line
			(start -1.549908 1.549908)
			(end -1.549908 -1.549908)
			(stroke
				(width 0.1)
				(type default)
			)
			(layer "F.Fab")
		)
		(fp_poly
			(pts
				(xy -3.4798 -1.359916) (xy -2.86004 -1.050036) (xy -3.4798 -0.740156)
			)
			(stroke
				(width 0)
				(type default)
			)
			(fill yes)
			(layer "F.Fab")
		)
		(pad "1" smd rect
			(at -2.175002 -1.050036 180)
			(size 0.6096 1.1684)
			(layers "F.Cu" "F.Mask" "F.Paste")
			(net "P1V8_PEX")
		)
		(pad "2" smd rect
			(at -2.175002 -0.32512 180)
			(size 0.4318 1.1684)
			(layers "F.Cu" "F.Mask" "F.Paste")
			(net "SMB_PEX_LS_SCL")
		)
		(pad "3" smd rect
			(at -2.175002 0.32512 180)
			(size 0.4318 1.1684)
			(layers "F.Cu" "F.Mask" "F.Paste")
			(net "SMB_PEX_LS_SDA")
		)
		(pad "4" smd rect
			(at -2.175002 1.050036 180)
			(size 0.6096 1.1684)
			(layers "F.Cu" "F.Mask" "F.Paste")
			(net "GND")
		)
		(pad "5" smd rect
			(at 2.175002 1.050036 180)
			(size 0.6096 1.1684)
			(layers "F.Cu" "F.Mask" "F.Paste")
			(net "PWRGD_P1V8_PEX_R1")
		)
		(pad "6" smd rect
			(at 2.175002 0.32512 180)
			(size 0.4318 1.1684)
			(layers "F.Cu" "F.Mask" "F.Paste")
			(net "SMB_PEX_R_SDA")
		)
		(pad "7" smd rect
			(at 2.175002 -0.32512 180)
			(size 0.4318 1.1684)
			(layers "F.Cu" "F.Mask" "F.Paste")
			(net "SMB_PEX_R_SCL")
		)
		(pad "8" smd rect
			(at 2.175002 -1.050036 180)
			(size 0.6096 1.1684)
			(layers "F.Cu" "F.Mask" "F.Paste")
			(net "P3V3_AUX")
		)
	)
	(footprint ""
		(layer "F.Cu")
		(at 4.781804 -59.557158 90)
		(property "Reference" "C2885"
			(at 0 0 90)
			(layer "F.SilkS")
			(hide yes)
			(effects
				(font
					(size 1.27 1.27)
				)
			)
		)
		(property "Value" ""
			(at 0 0 90)
			(layer "F.Fab")
			(effects
				(font
					(size 1.27 1.27)
				)
			)
		)
		(duplicate_pad_numbers_are_jumpers no)
		(fp_line
			(start 0.7874 -0.4064)
			(end 0.7874 0.4064)
			(stroke
				(width 0.1524)
				(type default)
			)
			(layer "F.SilkS")
		)
		(fp_line
			(start -0.7874 -0.4064)
			(end 0.7874 -0.4064)
			(stroke
				(width 0.1524)
				(type default)
			)
			(layer "F.SilkS")
		)
		(fp_line
			(start 0.7874 0.4064)
			(end -0.7874 0.4064)
			(stroke
				(width 0.1524)
				(type default)
			)
			(layer "F.SilkS")
		)
		(fp_line
			(start -0.7874 0.4064)
			(end -0.7874 -0.4064)
			(stroke
				(width 0.1524)
				(type default)
			)
			(layer "F.SilkS")
		)
		(fp_line
			(start -0.12065 -0.305054)
			(end -0.12065 -0.2794)
			(stroke
				(width 0.1)
				(type default)
			)
			(layer "F.Fab")
		)
		(fp_line
			(start -0.67945 -0.305054)
			(end -0.12065 -0.305054)
			(stroke
				(width 0.1)
				(type default)
			)
			(layer "F.Fab")
		)
		(fp_line
			(start 0.67945 -0.3048)
			(end 0.67945 0.3048)
			(stroke
				(width 0.1)
				(type default)
			)
			(layer "F.Fab")
		)
		(fp_line
			(start 0.12065 -0.3048)
			(end 0.67945 -0.3048)
			(stroke
				(width 0.1)
				(type default)
			)
			(layer "F.Fab")
		)
		(fp_line
			(start 0.12065 -0.2794)
			(end 0.12065 -0.3048)
			(stroke
				(width 0.1)
				(type default)
			)
			(layer "F.Fab")
		)
		(fp_line
			(start -0.12065 -0.2794)
			(end 0.12065 -0.2794)
			(stroke
				(width 0.1)
				(type default)
			)
			(layer "F.Fab")
		)
		(fp_line
			(start 0.120396 0.2794)
			(end -0.12065 0.2794)
			(stroke
				(width 0.1)
				(type default)
			)
			(layer "F.Fab")
		)
		(fp_line
			(start -0.12065 0.2794)
			(end -0.12065 0.3048)
			(stroke
				(width 0.1)
				(type default)
			)
			(layer "F.Fab")
		)
		(fp_line
			(start 0.67945 0.3048)
			(end 0.120396 0.3048)
			(stroke
				(width 0.1)
				(type default)
			)
			(layer "F.Fab")
		)
		(fp_line
			(start 0.120396 0.3048)
			(end 0.120396 0.2794)
			(stroke
				(width 0.1)
				(type default)
			)
			(layer "F.Fab")
		)
		(fp_line
			(start -0.12065 0.3048)
			(end -0.67945 0.3048)
			(stroke
				(width 0.1)
				(type default)
			)
			(layer "F.Fab")
		)
		(fp_line
			(start -0.67945 0.3048)
			(end -0.67945 -0.305054)
			(stroke
				(width 0.1)
				(type default)
			)
			(layer "F.Fab")
		)
		(pad "1" smd circle
			(at -0.40005 0 90)
			(size 0 0)
			(layers "F.Cu" "F.Mask" "F.Paste")
			(net "SSD0_AUX_P3V3_EN_R")
		)
		(pad "2" smd circle
			(at 0.40005 0 90)
			(size 0 0)
			(layers "F.Cu" "F.Mask" "F.Paste")
			(net "GND")
		)
	)
	(footprint ""
		(layer "F.Cu")
		(at 219.202 -196.596)
		(property "Reference" "R1524"
			(at 0 0 0)
			(layer "F.SilkS")
			(hide yes)
			(effects
				(font
					(size 1.27 1.27)
				)
			)
		)
		(property "Value" ""
			(at 0 0 0)
			(layer "F.Fab")
			(effects
				(font
					(size 1.27 1.27)
				)
			)
		)
		(duplicate_pad_numbers_are_jumpers no)
		(fp_line
			(start -0.7874 -0.4064)
			(end 0.7874 -0.4064)
			(stroke
				(width 0.1524)
				(type default)
			)
			(layer "F.SilkS")
		)
		(fp_line
			(start -0.7874 0.4064)
			(end -0.7874 -0.4064)
			(stroke
				(width 0.1524)
				(type default)
			)
			(layer "F.SilkS")
		)
		(fp_line
			(start 0.7874 -0.4064)
			(end 0.7874 0.4064)
			(stroke
				(width 0.1524)
				(type default)
			)
			(layer "F.SilkS")
		)
		(fp_line
			(start 0.7874 0.4064)
			(end -0.7874 0.4064)
			(stroke
				(width 0.1524)
				(type default)
			)
			(layer "F.SilkS")
		)
		(fp_line
			(start -0.67945 -0.305054)
			(end -0.12065 -0.305054)
			(stroke
				(width 0.1)
				(type default)
			)
			(layer "F.Fab")
		)
		(fp_line
			(start -0.67945 0.3048)
			(end -0.67945 -0.305054)
			(stroke
				(width 0.1)
				(type default)
			)
			(layer "F.Fab")
		)
		(fp_line
			(start -0.12065 -0.305054)
			(end -0.12065 -0.2794)
			(stroke
				(width 0.1)
				(type default)
			)
			(layer "F.Fab")
		)
		(fp_line
			(start -0.12065 -0.2794)
			(end 0.12065 -0.2794)
			(stroke
				(width 0.1)
				(type default)
			)
			(layer "F.Fab")
		)
		(fp_line
			(start -0.12065 0.2794)
			(end -0.12065 0.3048)
			(stroke
				(width 0.1)
				(type default)
			)
			(layer "F.Fab")
		)
		(fp_line
			(start -0.12065 0.3048)
			(end -0.67945 0.3048)
			(stroke
				(width 0.1)
				(type default)
			)
			(layer "F.Fab")
		)
		(fp_line
			(start 0.120396 0.2794)
			(end -0.12065 0.2794)
			(stroke
				(width 0.1)
				(type default)
			)
			(layer "F.Fab")
		)
		(fp_line
			(start 0.120396 0.3048)
			(end 0.120396 0.2794)
			(stroke
				(width 0.1)
				(type default)
			)
			(layer "F.Fab")
		)
		(fp_line
			(start 0.12065 -0.3048)
			(end 0.67945 -0.3048)
			(stroke
				(width 0.1)
				(type default)
			)
			(layer "F.Fab")
		)
		(fp_line
			(start 0.12065 -0.2794)
			(end 0.12065 -0.3048)
			(stroke
				(width 0.1)
				(type default)
			)
			(layer "F.Fab")
		)
		(fp_line
			(start 0.67945 -0.3048)
			(end 0.67945 0.3048)
			(stroke
				(width 0.1)
				(type default)
			)
			(layer "F.Fab")
		)
		(fp_line
			(start 0.67945 0.3048)
			(end 0.120396 0.3048)
			(stroke
				(width 0.1)
				(type default)
			)
			(layer "F.Fab")
		)
		(pad "1" smd circle
			(at -0.40005 0)
			(size 0 0)
			(layers "F.Cu" "F.Mask" "F.Paste")
			(net "SMB_NIC6_LS_EN")
		)
		(pad "2" smd circle
			(at 0.40005 0)
			(size 0 0)
			(layers "F.Cu" "F.Mask" "F.Paste")
			(net "P3V3_NIC6")
		)
	)
	(footprint ""
		(layer "F.Cu")
		(at 134.01167 -146.263614 180)
		(property "Reference" "C416"
			(at 0 0 180)
			(layer "F.SilkS")
			(hide yes)
			(effects
				(font
					(size 1.27 1.27)
				)
			)
		)
		(property "Value" ""
			(at 0 0 180)
			(layer "F.Fab")
			(effects
				(font
					(size 1.27 1.27)
				)
			)
		)
		(duplicate_pad_numbers_are_jumpers no)
		(fp_line
			(start 0.7874 0.4064)
			(end -0.7874 0.4064)
			(stroke
				(width 0.1524)
				(type default)
			)
			(layer "F.SilkS")
		)
		(fp_line
			(start 0.7874 -0.4064)
			(end 0.7874 0.4064)
			(stroke
				(width 0.1524)
				(type default)
			)
			(layer "F.SilkS")
		)
		(fp_line
			(start -0.7874 0.4064)
			(end -0.7874 -0.4064)
			(stroke
				(width 0.1524)
				(type default)
			)
			(layer "F.SilkS")
		)
		(fp_line
			(start -0.7874 -0.4064)
			(end 0.7874 -0.4064)
			(stroke
				(width 0.1524)
				(type default)
			)
			(layer "F.SilkS")
		)
		(fp_line
			(start 0.67945 0.3048)
			(end 0.120396 0.3048)
			(stroke
				(width 0.1)
				(type default)
			)
			(layer "F.Fab")
		)
		(fp_line
			(start 0.67945 -0.3048)
			(end 0.67945 0.3048)
			(stroke
				(width 0.1)
				(type default)
			)
			(layer "F.Fab")
		)
		(fp_line
			(start 0.12065 -0.2794)
			(end 0.12065 -0.3048)
			(stroke
				(width 0.1)
				(type default)
			)
			(layer "F.Fab")
		)
		(fp_line
			(start 0.12065 -0.3048)
			(end 0.67945 -0.3048)
			(stroke
				(width 0.1)
				(type default)
			)
			(layer "F.Fab")
		)
		(fp_line
			(start 0.120396 0.3048)
			(end 0.120396 0.2794)
			(stroke
				(width 0.1)
				(type default)
			)
			(layer "F.Fab")
		)
		(fp_line
			(start 0.120396 0.2794)
			(end -0.12065 0.2794)
			(stroke
				(width 0.1)
				(type default)
			)
			(layer "F.Fab")
		)
		(fp_line
			(start -0.12065 0.3048)
			(end -0.67945 0.3048)
			(stroke
				(width 0.1)
				(type default)
			)
			(layer "F.Fab")
		)
		(fp_line
			(start -0.12065 0.2794)
			(end -0.12065 0.3048)
			(stroke
				(width 0.1)
				(type default)
			)
			(layer "F.Fab")
		)
		(fp_line
			(start -0.12065 -0.2794)
			(end 0.12065 -0.2794)
			(stroke
				(width 0.1)
				(type default)
			)
			(layer "F.Fab")
		)
		(fp_line
			(start -0.12065 -0.305054)
			(end -0.12065 -0.2794)
			(stroke
				(width 0.1)
				(type default)
			)
			(layer "F.Fab")
		)
		(fp_line
			(start -0.67945 0.3048)
			(end -0.67945 -0.305054)
			(stroke
				(width 0.1)
				(type default)
			)
			(layer "F.Fab")
		)
		(fp_line
			(start -0.67945 -0.305054)
			(end -0.12065 -0.305054)
			(stroke
				(width 0.1)
				(type default)
			)
			(layer "F.Fab")
		)
		(pad "1" smd circle
			(at -0.40005 0 180)
			(size 0 0)
			(layers "F.Cu" "F.Mask" "F.Paste")
			(net "P12V_NIC2_R")
		)
		(pad "2" smd circle
			(at 0.40005 0 180)
			(size 0 0)
			(layers "F.Cu" "F.Mask" "F.Paste")
			(net "GND")
		)
	)
	(footprint ""
		(layer "F.Cu")
		(at 120.194324 -303.649634 90)
		(property "Reference" "PC101"
			(at 0 0 90)
			(layer "F.SilkS")
			(hide yes)
			(effects
				(font
					(size 1.27 1.27)
				)
			)
		)
		(property "Value" ""
			(at 0 0 90)
			(layer "F.Fab")
			(effects
				(font
					(size 1.27 1.27)
				)
			)
		)
		(duplicate_pad_numbers_are_jumpers no)
		(fp_line
			(start 1.524 -0.762)
			(end 1.524 0.762)
			(stroke
				(width 0.1524)
				(type default)
			)
			(layer "F.SilkS")
		)
		(fp_line
			(start -1.524 -0.762)
			(end 1.524 -0.762)
			(stroke
				(width 0.1524)
				(type default)
			)
			(layer "F.SilkS")
		)
		(fp_line
			(start 1.524 0.762)
			(end -1.524 0.762)
			(stroke
				(width 0.1524)
				(type default)
			)
			(layer "F.SilkS")
		)
		(fp_line
			(start -1.524 0.762)
			(end -1.524 -0.762)
			(stroke
				(width 0.1524)
				(type default)
			)
			(layer "F.SilkS")
		)
		(fp_line
			(start 1.1049 -0.724916)
			(end -1.1049 -0.724916)
			(stroke
				(width 0.1)
				(type default)
			)
			(layer "F.Fab")
		)
		(fp_line
			(start -1.1049 -0.724916)
			(end -1.1049 0.724916)
			(stroke
				(width 0.1)
				(type default)
			)
			(layer "F.Fab")
		)
		(fp_line
			(start 1.1049 0.724916)
			(end 1.1049 -0.724916)
			(stroke
				(width 0.1)
				(type default)
			)
			(layer "F.Fab")
		)
		(fp_line
			(start -1.1049 0.724916)
			(end 1.1049 0.724916)
			(stroke
				(width 0.1)
				(type default)
			)
			(layer "F.Fab")
		)
		(pad "1" smd rect
			(at -0.889 0 270)
			(size 1.016 1.27)
			(layers "F.Cu" "F.Mask" "F.Paste")
			(net "P0V8_PEX1")
		)
		(pad "2" smd rect
			(at 0.889 0 270)
			(size 1.016 1.27)
			(layers "F.Cu" "F.Mask" "F.Paste")
			(net "GND")
		)
	)
)
